(kicad_pcb
	(version 20260206)
	(generator "pcbnew")
	(generator_version "10.0")
	(general
		(thickness 1.6)
		(legacy_teardrops no)
	)
	(paper "A4")
	(title_block
		(title "baseboard — 13948-1b.1110WZS1818.brd")
		(comment 1 "Honey Badger (Wiwynn) / footprints 1189-1192 of 2523")
	)
	(layers
		(0 "F.Cu" signal "TOP")
		(4 "In1.Cu" signal "L2GND")
		(6 "In2.Cu" signal "L3")
		(8 "In3.Cu" signal "L4VCC")
		(10 "In4.Cu" signal "L5VCC")
		(12 "In5.Cu" signal "L6")
		(14 "In6.Cu" signal "L7GND")
		(2 "B.Cu" signal "BOTTOM")
		(9 "F.Adhes" user "F.Adhesive")
		(11 "B.Adhes" user "B.Adhesive")
		(13 "F.Paste" user "Package Geometry/Pastemask Top")
		(15 "B.Paste" user "Package Geometry/Pastemask Bottom")
		(5 "F.SilkS" user "Ref Des/Silkscreen Top")
		(7 "B.SilkS" user "Ref Des/Silkscreen Bottom")
		(1 "F.Mask" user "Board Geometry/Soldermask Top")
		(3 "B.Mask" user "Board Geometry/Soldermask Bottom")
		(17 "Dwgs.User" user "User.Drawings")
		(19 "Cmts.User" user "User.Comments")
		(21 "Eco1.User" user "User.Eco1")
		(23 "Eco2.User" user "User.Eco2")
		(25 "Edge.Cuts" user "Board Geometry/Outline")
		(27 "Margin" user)
		(31 "F.CrtYd" user "Package Geometry/Place Bound Top")
		(29 "B.CrtYd" user "Package Geometry/Place Bound Bottom")
		(35 "F.Fab" user "Ref Des/Assembly Top")
		(33 "B.Fab" user "Ref Des/Assembly Bottom")
	)
	(footprint ""
		(layer "F.Cu")
		(at 191.897 -22.479 -90)
		(property "Reference" "R646"
			(at 0 0 270)
			(layer "F.SilkS")
			(hide yes)
			(effects
				(font
					(size 1.27 1.27)
				)
			)
		)
		(property "Value" "0R2J-2-GP"
			(at 0.064008 -3.993896 270)
			(unlocked yes)
			(layer "F.Fab")
			(hide yes)
			(effects
				(font
					(size 1.016 1.016)
					(thickness 0.1524)
				)
			)
		)
		(property "Device Type" "R402H16"
			(at 0.064008 -5.517896 270)
			(unlocked yes)
			(layer "F.Fab")
			(hide yes)
			(effects
				(font
					(size 1.016 1.016)
					(thickness 0.1524)
				)
			)
		)
		(duplicate_pad_numbers_are_jumpers no)
		(fp_line
			(start -0.508 -0.9398)
			(end -0.508 0.9398)
			(stroke
				(width 0.1524)
				(type default)
			)
			(layer "F.SilkS")
		)
		(fp_line
			(start 0.508 -0.9398)
			(end -0.508 -0.9398)
			(stroke
				(width 0.1524)
				(type default)
			)
			(layer "F.SilkS")
		)
		(fp_rect
			(start -0.508 0.9398)
			(end 0.508 -0.9398)
			(stroke
				(width 0)
				(type default)
			)
			(fill no)
			(layer "F.CrtYd")
		)
		(fp_rect
			(start -0.508 0.9398)
			(end 0.508 -0.9398)
			(stroke
				(width 0)
				(type default)
			)
			(fill no)
			(layer "F.Fab")
		)
		(pad "1" smd custom
			(at 0 -0.4445 270)
			(size 0.1397 0.1397)
			(layers "F.Cu" "F.Mask" "F.Paste")
			(net "GND")
			(options
				(clearance outline)
				(anchor circle)
			)
			(primitives
				(gr_poly
					(pts
						(arc
							(start -0.1778 -0.2794)
							(mid -0.249642 -0.249642)
							(end -0.2794 -0.1778)
						)
						(arc
							(start -0.2794 0.1778)
							(mid -0.249642 0.249642)
							(end -0.1778 0.2794)
						)
						(arc
							(start 0.1778 0.2794)
							(mid 0.249642 0.249642)
							(end 0.2794 0.1778)
						)
						(arc
							(start 0.2794 -0.1778)
							(mid 0.249642 -0.249642)
							(end 0.1778 -0.2794)
						)
					)
					(width 0)
					(fill yes)
				)
			)
		)
		(pad "2" smd custom
			(at 0 0.4445 270)
			(size 0.1397 0.1397)
			(layers "F.Cu" "F.Mask" "F.Paste")
			(net "RMII_BMC_MDC")
			(options
				(clearance outline)
				(anchor circle)
			)
			(primitives
				(gr_poly
					(pts
						(arc
							(start -0.1778 -0.2794)
							(mid -0.249642 -0.249642)
							(end -0.2794 -0.1778)
						)
						(arc
							(start -0.2794 0.1778)
							(mid -0.249642 0.249642)
							(end -0.1778 0.2794)
						)
						(arc
							(start 0.1778 0.2794)
							(mid 0.249642 0.249642)
							(end 0.2794 0.1778)
						)
						(arc
							(start 0.2794 -0.1778)
							(mid 0.249642 -0.249642)
							(end 0.1778 -0.2794)
						)
					)
					(width 0)
					(fill yes)
				)
			)
		)
	)
	(footprint ""
		(layer "F.Cu")
		(at 144.907 -103.505 90)
		(property "Reference" "SC1188"
			(at 0 0 90)
			(layer "F.SilkS")
			(hide yes)
			(effects
				(font
					(size 1.27 1.27)
				)
			)
		)
		(property "Value" "SC100U6D3V0MX-2GP"
			(at -0.00254 -4.78536 90)
			(unlocked yes)
			(layer "F.Fab")
			(hide yes)
			(effects
				(font
					(size 1.016 1.016)
					(thickness 0.1524)
				)
			)
		)
		(property "Device Type" "C1210H107"
			(at -0.00254 -6.38048 90)
			(unlocked yes)
			(layer "F.Fab")
			(hide yes)
			(effects
				(font
					(size 1.016 1.016)
					(thickness 0.1524)
				)
			)
		)
		(duplicate_pad_numbers_are_jumpers no)
		(fp_line
			(start 1.5748 -2.3368)
			(end -1.5748 -2.3368)
			(stroke
				(width 0.1524)
				(type default)
			)
			(layer "F.SilkS")
		)
		(fp_line
			(start -1.5748 -2.3368)
			(end -1.5748 -0.762)
			(stroke
				(width 0.1524)
				(type default)
			)
			(layer "F.SilkS")
		)
		(fp_line
			(start 1.5748 -0.762)
			(end 1.5748 -2.3368)
			(stroke
				(width 0.1524)
				(type default)
			)
			(layer "F.SilkS")
		)
		(fp_line
			(start -1.5748 0.762)
			(end -1.5748 2.3368)
			(stroke
				(width 0.1524)
				(type default)
			)
			(layer "F.SilkS")
		)
		(fp_line
			(start 1.5748 2.3368)
			(end 1.5748 0.762)
			(stroke
				(width 0.1524)
				(type default)
			)
			(layer "F.SilkS")
		)
		(fp_line
			(start -1.5748 2.3368)
			(end 1.5748 2.3368)
			(stroke
				(width 0.1524)
				(type default)
			)
			(layer "F.SilkS")
		)
		(fp_rect
			(start -1.651 2.413)
			(end 1.651 -2.413)
			(stroke
				(width 0)
				(type default)
			)
			(fill no)
			(layer "F.CrtYd")
		)
		(fp_poly
			(pts
				(xy 1.651 2.413) (xy 1.651 -2.413) (xy -1.651 -2.413) (xy -1.651 2.413)
			)
			(stroke
				(width 0)
				(type default)
			)
			(fill no)
			(layer "F.Fab")
		)
		(pad "1" smd rect
			(at 0 -1.4732 90)
			(size 2.794 1.397)
			(layers "F.Cu" "F.Mask" "F.Paste")
			(net "GND")
		)
		(pad "2" smd rect
			(at 0 1.4732 90)
			(size 2.794 1.397)
			(layers "F.Cu" "F.Mask" "F.Paste")
			(net "GB_VDDA")
		)
	)
	(footprint ""
		(layer "F.Cu")
		(at 261.62 -16.383 180)
		(property "Reference" "TC10"
			(at 0 0 180)
			(layer "F.SilkS")
			(hide yes)
			(effects
				(font
					(size 1.27 1.27)
				)
			)
		)
		(property "Value" "SC47U16V0MX-GP"
			(at -0.00254 -4.78536 180)
			(unlocked yes)
			(layer "F.Fab")
			(hide yes)
			(effects
				(font
					(size 1.016 1.016)
					(thickness 0.1524)
				)
			)
		)
		(property "Device Type" "C1210H107"
			(at -0.00254 -6.38048 180)
			(unlocked yes)
			(layer "F.Fab")
			(hide yes)
			(effects
				(font
					(size 1.016 1.016)
					(thickness 0.1524)
				)
			)
		)
		(duplicate_pad_numbers_are_jumpers no)
		(fp_line
			(start 1.5748 2.3368)
			(end 1.5748 0.762)
			(stroke
				(width 0.1524)
				(type default)
			)
			(layer "F.SilkS")
		)
		(fp_line
			(start 1.5748 -0.762)
			(end 1.5748 -2.3368)
			(stroke
				(width 0.1524)
				(type default)
			)
			(layer "F.SilkS")
		)
		(fp_line
			(start 1.5748 -2.3368)
			(end -1.5748 -2.3368)
			(stroke
				(width 0.1524)
				(type default)
			)
			(layer "F.SilkS")
		)
		(fp_line
			(start -1.5748 2.3368)
			(end 1.5748 2.3368)
			(stroke
				(width 0.1524)
				(type default)
			)
			(layer "F.SilkS")
		)
		(fp_line
			(start -1.5748 0.762)
			(end -1.5748 2.3368)
			(stroke
				(width 0.1524)
				(type default)
			)
			(layer "F.SilkS")
		)
		(fp_line
			(start -1.5748 -2.3368)
			(end -1.5748 -0.762)
			(stroke
				(width 0.1524)
				(type default)
			)
			(layer "F.SilkS")
		)
		(fp_rect
			(start -1.651 2.413)
			(end 1.651 -2.413)
			(stroke
				(width 0)
				(type default)
			)
			(fill no)
			(layer "F.CrtYd")
		)
		(fp_poly
			(pts
				(xy 1.651 2.413) (xy 1.651 -2.413) (xy -1.651 -2.413) (xy -1.651 2.413)
			)
			(stroke
				(width 0)
				(type default)
			)
			(fill no)
			(layer "F.Fab")
		)
		(pad "1" smd rect
			(at 0 -1.4732 180)
			(size 2.794 1.397)
			(layers "F.Cu" "F.Mask" "F.Paste")
			(net "P5V_USB")
		)
		(pad "2" smd rect
			(at 0 1.4732 180)
			(size 2.794 1.397)
			(layers "F.Cu" "F.Mask" "F.Paste")
			(net "GND")
		)
	)
	(footprint ""
		(layer "F.Cu")
		(at 189.865 -25.273 90)
		(property "Reference" "R376"
			(at 0 0 90)
			(layer "F.SilkS")
			(hide yes)
			(effects
				(font
					(size 1.27 1.27)
				)
			)
		)
		(property "Value" "33R2J-2-GP"
			(at 0.064008 -3.993896 90)
			(unlocked yes)
			(layer "F.Fab")
			(hide yes)
			(effects
				(font
					(size 1.016 1.016)
					(thickness 0.1524)
				)
			)
		)
		(property "Device Type" "R402H16"
			(at 0.064008 -5.517896 90)
			(unlocked yes)
			(layer "F.Fab")
			(hide yes)
			(effects
				(font
					(size 1.016 1.016)
					(thickness 0.1524)
				)
			)
		)
		(duplicate_pad_numbers_are_jumpers no)
		(fp_line
			(start 0.508 -0.9398)
			(end -0.508 -0.9398)
			(stroke
				(width 0.1524)
				(type default)
			)
			(layer "F.SilkS")
		)
		(fp_line
			(start -0.508 -0.9398)
			(end -0.508 0.9398)
			(stroke
				(width 0.1524)
				(type default)
			)
			(layer "F.SilkS")
		)
		(fp_rect
			(start -0.508 0.9398)
			(end 0.508 -0.9398)
			(stroke
				(width 0)
				(type default)
			)
			(fill no)
			(layer "F.CrtYd")
		)
		(fp_rect
			(start -0.508 0.9398)
			(end 0.508 -0.9398)
			(stroke
				(width 0)
				(type default)
			)
			(fill no)
			(layer "F.Fab")
		)
		(pad "1" smd custom
			(at 0 -0.4445 90)
			(size 0.1397 0.1397)
			(layers "F.Cu" "F.Mask" "F.Paste")
			(net "RMII_PHY_BMC_RXD0_R")
			(options
				(clearance outline)
				(anchor circle)
			)
			(primitives
				(gr_poly
					(pts
						(arc
							(start -0.1778 -0.2794)
							(mid -0.249642 -0.249642)
							(end -0.2794 -0.1778)
						)
						(arc
							(start -0.2794 0.1778)
							(mid -0.249642 0.249642)
							(end -0.1778 0.2794)
						)
						(arc
							(start 0.1778 0.2794)
							(mid 0.249642 0.249642)
							(end 0.2794 0.1778)
						)
						(arc
							(start 0.2794 -0.1778)
							(mid 0.249642 -0.249642)
							(end 0.1778 -0.2794)
						)
					)
					(width 0)
					(fill yes)
				)
			)
		)
		(pad "2" smd custom
			(at 0 0.4445 90)
			(size 0.1397 0.1397)
			(layers "F.Cu" "F.Mask" "F.Paste")
			(net "RMII_PHY_BMC_RXD0")
			(options
				(clearance outline)
				(anchor circle)
			)
			(primitives
				(gr_poly
					(pts
						(arc
							(start -0.1778 -0.2794)
							(mid -0.249642 -0.249642)
							(end -0.2794 -0.1778)
						)
						(arc
							(start -0.2794 0.1778)
							(mid -0.249642 0.249642)
							(end -0.1778 0.2794)
						)
						(arc
							(start 0.1778 0.2794)
							(mid 0.249642 0.249642)
							(end 0.2794 0.1778)
						)
						(arc
							(start 0.2794 -0.1778)
							(mid 0.249642 -0.249642)
							(end 0.1778 -0.2794)
						)
					)
					(width 0)
					(fill yes)
				)
			)
		)
	)
)
